(kicad_pcb
	(version 20260206)
	(generator "pcbnew")
	(generator_version "10.0")
	(general
		(thickness 1.6)
		(legacy_teardrops no)
	)
	(paper "A4")
	(title_block
		(title "Wiwynn_Tioga_Pass_MB.brd")
		(comment 1 "Tioga Pass / footprints 4365-4369 of 4770")
	)
	(layers
		(0 "F.Cu" signal "TOP")
		(4 "In1.Cu" signal "L2GND")
		(6 "In2.Cu" signal "L3")
		(8 "In3.Cu" signal "L4GND")
		(10 "In4.Cu" signal "L5")
		(12 "In5.Cu" signal "L6GND")
		(14 "In6.Cu" signal "L7VCC")
		(16 "In7.Cu" signal "L8VCC")
		(18 "In8.Cu" signal "L9GND")
		(20 "In9.Cu" signal "L10")
		(22 "In10.Cu" signal "L11GND")
		(24 "In11.Cu" signal "L12")
		(26 "In12.Cu" signal "L13GND")
		(2 "B.Cu" signal "BOTTOM")
		(9 "F.Adhes" user "F.Adhesive")
		(11 "B.Adhes" user "B.Adhesive")
		(13 "F.Paste" user "Package Geometry/Pastemask Top")
		(15 "B.Paste" user "Package Geometry/Pastemask Bottom")
		(5 "F.SilkS" user "Ref Des/Silkscreen Top")
		(7 "B.SilkS" user "Ref Des/Silkscreen Bottom")
		(1 "F.Mask" user "Board Geometry/Soldermask Top")
		(3 "B.Mask" user "Board Geometry/Soldermask Bottom")
		(17 "Dwgs.User" user "User.Drawings")
		(19 "Cmts.User" user "User.Comments")
		(21 "Eco1.User" user "User.Eco1")
		(23 "Eco2.User" user "User.Eco2")
		(25 "Edge.Cuts" user "Board Geometry/Outline")
		(27 "Margin" user)
		(31 "F.CrtYd" user "Package Geometry/Place Bound Top")
		(29 "B.CrtYd" user "Package Geometry/Place Bound Bottom")
		(35 "F.Fab" user "Ref Des/Assembly Top")
		(33 "B.Fab" user "Ref Des/Assembly Bottom")
	)
	(footprint ""
		(layer "B.Cu")
		(at 489.65739 -148.082 90)
		(property "Reference" "R1L11"
			(at 0 0 90)
			(layer "B.SilkS")
			(hide yes)
			(effects
				(font
					(size 1.27 1.27)
				)
				(justify mirror)
			)
		)
		(property "Value" ""
			(at 0 0 90)
			(layer "B.Fab")
			(effects
				(font
					(size 1.27 1.27)
				)
				(justify mirror)
			)
		)
		(duplicate_pad_numbers_are_jumpers no)
		(fp_poly
			(pts
				(xy 0.2794 -0.1016) (xy -0.2794 -0.1016) (xy -0.2794 0.9906) (xy 0.2794 0.9906)
			)
			(stroke
				(width 0)
				(type default)
			)
			(fill no)
			(layer "B.CrtYd")
		)
		(fp_line
			(start 0.2794 -0.1016)
			(end 0.2794 0.9906)
			(stroke
				(width 0.1)
				(type default)
			)
			(layer "B.Fab")
		)
		(fp_line
			(start -0.2794 -0.1016)
			(end 0.2794 -0.1016)
			(stroke
				(width 0.1)
				(type default)
			)
			(layer "B.Fab")
		)
		(fp_line
			(start 0.2794 0.9906)
			(end -0.2794 0.9906)
			(stroke
				(width 0.1)
				(type default)
			)
			(layer "B.Fab")
		)
		(fp_line
			(start -0.2794 0.9906)
			(end -0.2794 -0.1016)
			(stroke
				(width 0.1)
				(type default)
			)
			(layer "B.Fab")
		)
		(pad "1" smd rect
			(at 0 0 270)
			(size 0.508 0.508)
			(layers "B.Cu" "B.Mask" "B.Paste")
			(net "LED_POSTCODE_7")
		)
		(pad "2" smd rect
			(at 0 0.889 270)
			(size 0.508 0.508)
			(layers "B.Cu" "B.Mask" "B.Paste")
			(net "LED_POSTCODE_7_R")
		)
		(zone
			(layer "B.Cu")
			(hatch none 0.5)
			(connect_pads
				(clearance 0)
			)
			(min_thickness 0.25)
			(keepout
				(tracks allowed)
				(vias not_allowed)
				(pads allowed)
				(copperpour not_allowed)
				(footprints allowed)
			)
			(placement
				(enabled no)
				(sheetname "")
			)
			(fill
				(thermal_gap 0.5)
				(thermal_bridge_width 0.5)
				(island_removal_mode 0)
			)
			(polygon
				(pts
					(xy 489.91139 -148.336) (xy 489.91139 -147.828) (xy 490.29239 -147.828) (xy 490.29239 -148.336)
				)
			)
		)
		(zone
			(layer "B.Cu")
			(hatch none 0.5)
			(connect_pads
				(clearance 0)
			)
			(min_thickness 0.25)
			(keepout
				(tracks not_allowed)
				(vias allowed)
				(pads allowed)
				(copperpour not_allowed)
				(footprints allowed)
			)
			(placement
				(enabled no)
				(sheetname "")
			)
			(fill
				(thermal_gap 0.5)
				(thermal_bridge_width 0.5)
				(island_removal_mode 0)
			)
			(polygon
				(pts
					(xy 490.29239 -148.336) (xy 490.29239 -147.828) (xy 489.91139 -147.828) (xy 489.91139 -148.336)
				)
			)
		)
	)
	(footprint ""
		(layer "B.Cu")
		(at 459.753208 -136.144254 90)
		(property "Reference" "U1L5"
			(at 2.894076 -0.394208 0)
			(unlocked yes)
			(layer "B.SilkS")
			(effects
				(font
					(size 0.7874 0.5842)
					(thickness 0.1524)
				)
				(justify left mirror)
			)
		)
		(property "Value" ""
			(at 0 0 90)
			(layer "B.Fab")
			(effects
				(font
					(size 1.27 1.27)
				)
				(justify mirror)
			)
		)
		(duplicate_pad_numbers_are_jumpers no)
		(fp_circle
			(center 1.17856 -2.466086)
			(end 1.17856 -2.339086)
			(stroke
				(width 0.254)
				(type default)
			)
			(fill no)
			(layer "B.SilkS")
		)
		(fp_rect
			(start 0.9144 0.9144)
			(end -0.9144 -0.9144)
			(stroke
				(width 0)
				(type default)
			)
			(fill yes)
			(layer "B.Paste")
		)
		(fp_rect
			(start 1.82499 1.82499)
			(end -1.82499 -1.82499)
			(stroke
				(width 0)
				(type default)
			)
			(fill no)
			(layer "B.CrtYd")
		)
		(fp_line
			(start 1.82499 -1.82499)
			(end -1.82499 -1.82499)
			(stroke
				(width 0.1)
				(type default)
			)
			(layer "B.Fab")
		)
		(fp_line
			(start -1.82499 -1.82499)
			(end -1.82499 1.82499)
			(stroke
				(width 0.1)
				(type default)
			)
			(layer "B.Fab")
		)
		(fp_line
			(start 1.82499 1.82499)
			(end 1.82499 -1.82499)
			(stroke
				(width 0.1)
				(type default)
			)
			(layer "B.Fab")
		)
		(fp_line
			(start -1.82499 1.82499)
			(end 1.82499 1.82499)
			(stroke
				(width 0.1)
				(type default)
			)
			(layer "B.Fab")
		)
		(fp_circle
			(center 1.17856 -2.466086)
			(end 1.17856 -2.339086)
			(stroke
				(width 0.254)
				(type default)
			)
			(fill no)
			(layer "B.Fab")
		)
		(pad "1" smd custom
			(at 0.750062 -1.549908 270)
			(size 0.0762 0.0762)
			(layers "B.Cu" "B.Mask" "B.Paste")
			(net "PWRGD_PVCCIN_CPU0")
			(options
				(clearance outline)
				(anchor circle)
			)
			(primitives
				(gr_poly
					(pts
						(xy 0.1524 0.381)
						(arc
							(start 0.1524 -0.2286)
							(mid 0 -0.381)
							(end -0.1524 -0.2286)
						)
						(xy -0.1524 0.381)
					)
					(width 0)
					(fill yes)
				)
			)
		)
		(pad "2" smd custom
			(at 1.549908 -0.999998 270)
			(size 0.0762 0.0762)
			(layers "B.Cu" "B.Mask" "B.Paste")
			(net "XDP_OBSFN_B1_MBP7_N")
			(options
				(clearance outline)
				(anchor circle)
			)
			(primitives
				(gr_poly
					(pts
						(xy -0.381 0.1524)
						(arc
							(start 0.2286 0.1524)
							(mid 0.381 0)
							(end 0.2286 -0.1524)
						)
						(xy -0.381 -0.1524)
					)
					(width 0)
					(fill yes)
				)
			)
		)
		(pad "3" smd custom
			(at 1.549908 -0.500126 270)
			(size 0.0762 0.0762)
			(layers "B.Cu" "B.Mask" "B.Paste")
			(net "XDP_CPU_OBSFN_B1_MBP7_N")
			(options
				(clearance outline)
				(anchor circle)
			)
			(primitives
				(gr_poly
					(pts
						(xy -0.381 0.1524)
						(arc
							(start 0.2286 0.1524)
							(mid 0.381 0)
							(end 0.2286 -0.1524)
						)
						(xy -0.381 -0.1524)
					)
					(width 0)
					(fill yes)
				)
			)
		)
		(pad "4" smd custom
			(at 1.549908 0 270)
			(size 0.0762 0.0762)
			(layers "B.Cu" "B.Mask" "B.Paste")
			(net "PWRGD_PVCCIN_CPU0")
			(options
				(clearance outline)
				(anchor circle)
			)
			(primitives
				(gr_poly
					(pts
						(xy -0.381 0.1524)
						(arc
							(start 0.2286 0.1524)
							(mid 0.381 0)
							(end 0.2286 -0.1524)
						)
						(xy -0.381 -0.1524)
					)
					(width 0)
					(fill yes)
				)
			)
		)
		(pad "5" smd custom
			(at 1.549908 0.500126 270)
			(size 0.0762 0.0762)
			(layers "B.Cu" "B.Mask" "B.Paste")
			(net "XDP_OBSFN_B0_MBP6_N")
			(options
				(clearance outline)
				(anchor circle)
			)
			(primitives
				(gr_poly
					(pts
						(xy -0.381 0.1524)
						(arc
							(start 0.2286 0.1524)
							(mid 0.381 0)
							(end 0.2286 -0.1524)
						)
						(xy -0.381 -0.1524)
					)
					(width 0)
					(fill yes)
				)
			)
		)
		(pad "6" smd custom
			(at 1.549908 0.999998 270)
			(size 0.0762 0.0762)
			(layers "B.Cu" "B.Mask" "B.Paste")
			(net "XDP_CPU_OBSFN_B0_MBP6_N")
			(options
				(clearance outline)
				(anchor circle)
			)
			(primitives
				(gr_poly
					(pts
						(xy -0.381 0.1524)
						(arc
							(start 0.2286 0.1524)
							(mid 0.381 0)
							(end 0.2286 -0.1524)
						)
						(xy -0.381 -0.1524)
					)
					(width 0)
					(fill yes)
				)
			)
		)
		(pad "7" smd custom
			(at 0.750062 1.549908 270)
			(size 0.0762 0.0762)
			(layers "B.Cu" "B.Mask" "B.Paste")
			(net "GND")
			(options
				(clearance outline)
				(anchor circle)
			)
			(primitives
				(gr_poly
					(pts
						(xy -0.1524 -0.381)
						(arc
							(start -0.1524 0.2286)
							(mid 0 0.381)
							(end 0.1524 0.2286)
						)
						(xy 0.1524 -0.381)
					)
					(width 0)
					(fill yes)
				)
			)
		)
		(pad "8" smd custom
			(at -0.769874 1.549908 270)
			(size 0.0762 0.0762)
			(layers "B.Cu" "B.Mask" "B.Paste")
			(net "XDP_CPU_PRDY_N")
			(options
				(clearance outline)
				(anchor circle)
			)
			(primitives
				(gr_poly
					(pts
						(xy -0.1524 -0.381)
						(arc
							(start -0.1524 0.2286)
							(mid 0 0.381)
							(end 0.1524 0.2286)
						)
						(xy 0.1524 -0.381)
					)
					(width 0)
					(fill yes)
				)
			)
		)
		(pad "9" smd custom
			(at -1.549908 0.999998 270)
			(size 0.0762 0.0762)
			(layers "B.Cu" "B.Mask" "B.Paste")
			(net "XDP_PRDY_N")
			(options
				(clearance outline)
				(anchor circle)
			)
			(primitives
				(gr_poly
					(pts
						(xy 0.381 -0.1524)
						(arc
							(start -0.2286 -0.1524)
							(mid -0.381 0)
							(end -0.2286 0.1524)
						)
						(xy 0.381 0.1524)
					)
					(width 0)
					(fill yes)
				)
			)
		)
		(pad "10" smd custom
			(at -1.549908 0.500126 270)
			(size 0.0762 0.0762)
			(layers "B.Cu" "B.Mask" "B.Paste")
			(net "PWRGD_PVCCIN_CPU0")
			(options
				(clearance outline)
				(anchor circle)
			)
			(primitives
				(gr_poly
					(pts
						(xy 0.381 -0.1524)
						(arc
							(start -0.2286 -0.1524)
							(mid -0.381 0)
							(end -0.2286 0.1524)
						)
						(xy 0.381 0.1524)
					)
					(width 0)
					(fill yes)
				)
			)
		)
		(pad "11" smd custom
			(at -1.549908 0 270)
			(size 0.0762 0.0762)
			(layers "B.Cu" "B.Mask" "B.Paste")
			(net "XDP_CPU_PREQ_N")
			(options
				(clearance outline)
				(anchor circle)
			)
			(primitives
				(gr_poly
					(pts
						(xy 0.381 -0.1524)
						(arc
							(start -0.2286 -0.1524)
							(mid -0.381 0)
							(end -0.2286 0.1524)
						)
						(xy 0.381 0.1524)
					)
					(width 0)
					(fill yes)
				)
			)
		)
		(pad "12" smd custom
			(at -1.549908 -0.500126 270)
			(size 0.0762 0.0762)
			(layers "B.Cu" "B.Mask" "B.Paste")
			(net "XDP_PREQ_N")
			(options
				(clearance outline)
				(anchor circle)
			)
			(primitives
				(gr_poly
					(pts
						(xy 0.381 -0.1524)
						(arc
							(start -0.2286 -0.1524)
							(mid -0.381 0)
							(end -0.2286 0.1524)
						)
						(xy 0.381 0.1524)
					)
					(width 0)
					(fill yes)
				)
			)
		)
		(pad "13" smd custom
			(at -1.549908 -0.999998 270)
			(size 0.0762 0.0762)
			(layers "B.Cu" "B.Mask" "B.Paste")
			(net "PWRGD_PVCCIN_CPU0")
			(options
				(clearance outline)
				(anchor circle)
			)
			(primitives
				(gr_poly
					(pts
						(xy 0.381 -0.1524)
						(arc
							(start -0.2286 -0.1524)
							(mid -0.381 0)
							(end -0.2286 0.1524)
						)
						(xy 0.381 0.1524)
					)
					(width 0)
					(fill yes)
				)
			)
		)
		(pad "14" smd custom
			(at -0.750062 -1.549908 270)
			(size 0.0762 0.0762)
			(layers "B.Cu" "B.Mask" "B.Paste")
			(net "P3V3_STBY")
			(options
				(clearance outline)
				(anchor circle)
			)
			(primitives
				(gr_poly
					(pts
						(xy 0.1524 0.381)
						(arc
							(start 0.1524 -0.2286)
							(mid 0 -0.381)
							(end -0.1524 -0.2286)
						)
						(xy -0.1524 0.381)
					)
					(width 0)
					(fill yes)
				)
			)
		)
		(pad "15" smd rect
			(at 0 0 270)
			(size 1.8288 1.8288)
			(layers "B.Cu" "B.Mask" "B.Paste")
			(net "GND")
		)
	)
	(footprint ""
		(layer "B.Cu")
		(at 377.75642 -67.2211)
		(property "Reference" "R1W26"
			(at 0.8382 -0.67818 0)
			(unlocked yes)
			(layer "B.SilkS")
			(effects
				(font
					(size 0.4064 0.254)
					(thickness 0.1524)
				)
				(justify left mirror)
			)
		)
		(property "Value" ""
			(at 0 0 0)
			(layer "B.Fab")
			(effects
				(font
					(size 1.27 1.27)
				)
				(justify mirror)
			)
		)
		(duplicate_pad_numbers_are_jumpers no)
		(fp_poly
			(pts
				(xy 0.2794 -0.1016) (xy -0.2794 -0.1016) (xy -0.2794 0.9906) (xy 0.2794 0.9906)
			)
			(stroke
				(width 0)
				(type default)
			)
			(fill no)
			(layer "B.CrtYd")
		)
		(fp_line
			(start -0.2794 -0.1016)
			(end 0.2794 -0.1016)
			(stroke
				(width 0.1)
				(type default)
			)
			(layer "B.Fab")
		)
		(fp_line
			(start -0.2794 0.9906)
			(end -0.2794 -0.1016)
			(stroke
				(width 0.1)
				(type default)
			)
			(layer "B.Fab")
		)
		(fp_line
			(start 0.2794 -0.1016)
			(end 0.2794 0.9906)
			(stroke
				(width 0.1)
				(type default)
			)
			(layer "B.Fab")
		)
		(fp_line
			(start 0.2794 0.9906)
			(end -0.2794 0.9906)
			(stroke
				(width 0.1)
				(type default)
			)
			(layer "B.Fab")
		)
		(pad "1" smd rect
			(at 0 0 180)
			(size 0.508 0.508)
			(layers "B.Cu" "B.Mask" "B.Paste")
			(net "RST_RSMRST_R_N")
		)
		(pad "2" smd rect
			(at 0 0.889 180)
			(size 0.508 0.508)
			(layers "B.Cu" "B.Mask" "B.Paste")
			(net "GND")
		)
		(zone
			(layer "B.Cu")
			(hatch none 0.5)
			(connect_pads
				(clearance 0)
			)
			(min_thickness 0.25)
			(keepout
				(tracks allowed)
				(vias not_allowed)
				(pads allowed)
				(copperpour not_allowed)
				(footprints allowed)
			)
			(placement
				(enabled no)
				(sheetname "")
			)
			(fill
				(thermal_gap 0.5)
				(thermal_bridge_width 0.5)
				(island_removal_mode 0)
			)
			(polygon
				(pts
					(xy 378.01042 -66.9671) (xy 377.50242 -66.9671) (xy 377.50242 -66.5861) (xy 378.01042 -66.5861)
				)
			)
		)
		(zone
			(layer "B.Cu")
			(hatch none 0.5)
			(connect_pads
				(clearance 0)
			)
			(min_thickness 0.25)
			(keepout
				(tracks not_allowed)
				(vias allowed)
				(pads allowed)
				(copperpour not_allowed)
				(footprints allowed)
			)
			(placement
				(enabled no)
				(sheetname "")
			)
			(fill
				(thermal_gap 0.5)
				(thermal_bridge_width 0.5)
				(island_removal_mode 0)
			)
			(polygon
				(pts
					(xy 378.01042 -66.5861) (xy 377.50242 -66.5861) (xy 377.50242 -66.9671) (xy 378.01042 -66.9671)
				)
			)
		)
	)
	(footprint ""
		(layer "B.Cu")
		(at 367.925604 -151.694388)
		(property "Reference" "C7W12"
			(at 0 0 0)
			(layer "B.SilkS")
			(hide yes)
			(effects
				(font
					(size 1.27 1.27)
				)
				(justify mirror)
			)
		)
		(property "Value" "*"
			(at 0.0762 -6.2357 0)
			(unlocked yes)
			(layer "B.Fab")
			(hide yes)
			(effects
				(font
					(size 1.27 1.016)
					(thickness 0.1524)
				)
				(justify mirror)
			)
		)
		(property "Device Type" "SC22U16V5MX-4-GP_SMD-BCG5-SC22A"
			(at 0.0762 -8.2677 0)
			(unlocked yes)
			(layer "B.Fab")
			(hide yes)
			(effects
				(font
					(size 1.27 1.016)
					(thickness 0.1524)
				)
				(justify mirror)
			)
		)
		(duplicate_pad_numbers_are_jumpers no)
		(fp_line
			(start -0.635 0)
			(end 0.635 0)
			(stroke
				(width 0.508)
				(type default)
			)
			(layer "B.SilkS")
		)
		(fp_rect
			(start 0.9652 1.778)
			(end -0.9652 -1.778)
			(stroke
				(width 0)
				(type default)
			)
			(fill no)
			(layer "B.CrtYd")
		)
		(fp_poly
			(pts
				(xy 0.9652 -1.778) (xy -0.9652 -1.778) (xy -0.9652 1.778) (xy 0.9652 1.778)
			)
			(stroke
				(width 0)
				(type default)
			)
			(fill no)
			(layer "B.Fab")
		)
		(pad "1" smd rect
			(at 0 -0.9652 180)
			(size 1.397 1.143)
			(layers "B.Cu" "B.Mask" "B.Paste")
			(net "VR_FET_SW_P12V_STBY_PVDDQ_DEF")
		)
		(pad "2" smd rect
			(at 0 0.9652 180)
			(size 1.397 1.143)
			(layers "B.Cu" "B.Mask" "B.Paste")
			(net "GND")
		)
	)
	(footprint ""
		(layer "B.Cu")
		(at 479.9838 -43.4086 90)
		(property "Reference" "C1R21"
			(at 0 0 90)
			(layer "B.SilkS")
			(hide yes)
			(effects
				(font
					(size 1.27 1.27)
				)
				(justify mirror)
			)
		)
		(property "Value" ""
			(at 0 0 90)
			(layer "B.Fab")
			(effects
				(font
					(size 1.27 1.27)
				)
				(justify mirror)
			)
		)
		(duplicate_pad_numbers_are_jumpers no)
		(fp_poly
			(pts
				(xy -0.3048 -0.1016) (xy -0.3048 0.9906) (xy 0.3048 0.9906) (xy 0.3048 -0.1016)
			)
			(stroke
				(width 0)
				(type default)
			)
			(fill no)
			(layer "B.CrtYd")
		)
		(fp_line
			(start 0.3048 -0.1016)
			(end 0.3048 0.9906)
			(stroke
				(width 0.1)
				(type default)
			)
			(layer "B.Fab")
		)
		(fp_line
			(start -0.3048 -0.1016)
			(end 0.3048 -0.1016)
			(stroke
				(width 0.1)
				(type default)
			)
			(layer "B.Fab")
		)
		(fp_line
			(start 0.3048 0.9906)
			(end -0.3048 0.9906)
			(stroke
				(width 0.1)
				(type default)
			)
			(layer "B.Fab")
		)
		(fp_line
			(start -0.3048 0.9906)
			(end -0.3048 -0.1016)
			(stroke
				(width 0.1)
				(type default)
			)
			(layer "B.Fab")
		)
		(pad "1" smd rect
			(at 0 0 270)
			(size 0.508 0.508)
			(layers "B.Cu" "B.Mask" "B.Paste")
			(net "P3V3_STBY")
		)
		(pad "2" smd rect
			(at 0 0.889 270)
			(size 0.508 0.508)
			(layers "B.Cu" "B.Mask" "B.Paste")
			(net "GND")
		)
		(zone
			(layer "B.Cu")
			(hatch none 0.5)
			(connect_pads
				(clearance 0)
			)
			(min_thickness 0.25)
			(keepout
				(tracks allowed)
				(vias not_allowed)
				(pads allowed)
				(copperpour not_allowed)
				(footprints allowed)
			)
			(placement
				(enabled no)
				(sheetname "")
			)
			(fill
				(thermal_gap 0.5)
				(thermal_bridge_width 0.5)
				(island_removal_mode 0)
			)
			(polygon
				(pts
					(xy 480.2378 -43.6626) (xy 480.2378 -43.1546) (xy 480.6188 -43.1546) (xy 480.6188 -43.6626)
				)
			)
		)
		(zone
			(layer "B.Cu")
			(hatch none 0.5)
			(connect_pads
				(clearance 0)
			)
			(min_thickness 0.25)
			(keepout
				(tracks not_allowed)
				(vias allowed)
				(pads allowed)
				(copperpour not_allowed)
				(footprints allowed)
			)
			(placement
				(enabled no)
				(sheetname "")
			)
			(fill
				(thermal_gap 0.5)
				(thermal_bridge_width 0.5)
				(island_removal_mode 0)
			)
			(polygon
				(pts
					(xy 480.6188 -43.6626) (xy 480.6188 -43.1546) (xy 480.2378 -43.1546) (xy 480.2378 -43.6626)
				)
			)
		)
	)
)
